# S9S_MB_2U (Grand Teton) — schematic netlist excerpt (pin names and nets, part order shuffled) for the footprints in the layout excerpt that follows; sources: Cadence DE-HDL packaged netlist, KiCad conversion of 03242023_DA0F0TMBIJ0_F0T_Motherboard_J_brd_V01_OCP.brd

H95  HOLE  EMPTY  pkg TH  page 311 : \1\ = GND
R3354  Q_RES  0 5% CHIP  pkg 0402LF  page 207 : A = CLK_100M_GPU_2_R_DP ; B = CLK_100M_GPU_2_DP
C944  Q_CAP_DIFFBUS  DIFF BUS_0.22UF 6.3V 20% X6S  pkg C0201  page 173 : \1\ = P5E_CPU0_PE2_TX_C_DN<10> ; \2\ = P5E_CPU0_PE2_TX_DN<10>
PC2223  Q_CAP  1UF 25V 10% X6S  pkg C0402  page 303 : A = HSC_VDD_R_4 ; B = AGND_HSC

(kicad_pcb
	(version 20260206)
	(generator "pcbnew")
	(generator_version "10.0")
	(general
		(thickness 1.6)
		(legacy_teardrops no)
	)
	(paper "A4")
	(title_block
		(title "03242023_DA0F0TMBIJ0_F0T_Motherboard_J_brd_V01_OCP.brd")
		(comment 1 "Grand Teton / footprints 477-480 of 6105")
	)
	(layers
		(0 "F.Cu" signal "TOP")
		(4 "In1.Cu" signal "GND")
		(6 "In2.Cu" signal "IN1")
		(8 "In3.Cu" signal "GND1")
		(10 "In4.Cu" signal "IN2")
		(12 "In5.Cu" signal "GND2")
		(14 "In6.Cu" signal "IN3")
		(16 "In7.Cu" signal "GND3")
		(18 "In8.Cu" signal "VCC")
		(20 "In9.Cu" signal "VCC1")
		(22 "In10.Cu" signal "GND4")
		(24 "In11.Cu" signal "IN4")
		(26 "In12.Cu" signal "GND5")
		(28 "In13.Cu" signal "IN5")
		(30 "In14.Cu" signal "GND6")
		(32 "In15.Cu" signal "IN6")
		(34 "In16.Cu" signal "GND7")
		(2 "B.Cu" signal "BOTTOM")
		(9 "F.Adhes" user "F.Adhesive")
		(11 "B.Adhes" user "B.Adhesive")
		(13 "F.Paste" user "Package Geometry/Pastemask Top")
		(15 "B.Paste" user "Package Geometry/Pastemask Bottom")
		(5 "F.SilkS" user "Ref Des/Silkscreen Top")
		(7 "B.SilkS" user "Ref Des/Silkscreen Bottom")
		(1 "F.Mask" user "Board Geometry/Soldermask Top")
		(3 "B.Mask" user "Board Geometry/Soldermask Bottom")
		(17 "Dwgs.User" user "User.Drawings")
		(19 "Cmts.User" user "User.Comments")
		(21 "Eco1.User" user "User.Eco1")
		(23 "Eco2.User" user "User.Eco2")
		(25 "Edge.Cuts" user "Board Geometry/Outline")
		(27 "Margin" user)
		(31 "F.CrtYd" user "Package Geometry/Place Bound Top")
		(29 "B.CrtYd" user "Package Geometry/Place Bound Bottom")
		(35 "F.Fab" user "Ref Des/Assembly Top")
		(33 "B.Fab" user "Ref Des/Assembly Bottom")
	)
	(footprint ""
		(layer "F.Cu")
		(at 106.70921 -413.687768 180)
		(property "Reference" "R3354"
			(at 0 0 180)
			(layer "F.SilkS")
			(hide yes)
			(effects
				(font
					(size 1.27 1.27)
				)
			)
		)
		(property "Value" ""
			(at 0 0 180)
			(layer "F.Fab")
			(effects
				(font
					(size 1.27 1.27)
				)
			)
		)
		(duplicate_pad_numbers_are_jumpers no)
		(fp_line
			(start 0.7874 0.4064)
			(end -0.7874 0.4064)
			(stroke
				(width 0.1524)
				(type default)
			)
			(layer "F.SilkS")
		)
		(fp_line
			(start 0.7874 0.01016)
			(end 0.7874 0.4064)
			(stroke
				(width 0.1524)
				(type default)
			)
			(layer "F.SilkS")
		)
		(fp_line
			(start -0.40767 -0.4064)
			(end 0.44323 -0.4064)
			(stroke
				(width 0.1524)
				(type default)
			)
			(layer "F.SilkS")
		)
		(fp_line
			(start -0.7874 0.4064)
			(end -0.7874 -0.03556)
			(stroke
				(width 0.1524)
				(type default)
			)
			(layer "F.SilkS")
		)
		(fp_line
			(start 0.67945 0.3048)
			(end 0.120396 0.3048)
			(stroke
				(width 0.1)
				(type default)
			)
			(layer "F.Fab")
		)
		(fp_line
			(start 0.67945 -0.3048)
			(end 0.67945 0.3048)
			(stroke
				(width 0.1)
				(type default)
			)
			(layer "F.Fab")
		)
		(fp_line
			(start 0.12065 -0.2794)
			(end 0.12065 -0.3048)
			(stroke
				(width 0.1)
				(type default)
			)
			(layer "F.Fab")
		)
		(fp_line
			(start 0.12065 -0.3048)
			(end 0.67945 -0.3048)
			(stroke
				(width 0.1)
				(type default)
			)
			(layer "F.Fab")
		)
		(fp_line
			(start 0.120396 0.3048)
			(end 0.120396 0.2794)
			(stroke
				(width 0.1)
				(type default)
			)
			(layer "F.Fab")
		)
		(fp_line
			(start 0.120396 0.2794)
			(end -0.12065 0.2794)
			(stroke
				(width 0.1)
				(type default)
			)
			(layer "F.Fab")
		)
		(fp_line
			(start -0.12065 0.3048)
			(end -0.67945 0.3048)
			(stroke
				(width 0.1)
				(type default)
			)
			(layer "F.Fab")
		)
		(fp_line
			(start -0.12065 0.2794)
			(end -0.12065 0.3048)
			(stroke
				(width 0.1)
				(type default)
			)
			(layer "F.Fab")
		)
		(fp_line
			(start -0.12065 -0.2794)
			(end 0.12065 -0.2794)
			(stroke
				(width 0.1)
				(type default)
			)
			(layer "F.Fab")
		)
		(fp_line
			(start -0.12065 -0.305054)
			(end -0.12065 -0.2794)
			(stroke
				(width 0.1)
				(type default)
			)
			(layer "F.Fab")
		)
		(fp_line
			(start -0.67945 0.3048)
			(end -0.67945 -0.305054)
			(stroke
				(width 0.1)
				(type default)
			)
			(layer "F.Fab")
		)
		(fp_line
			(start -0.67945 -0.305054)
			(end -0.12065 -0.305054)
			(stroke
				(width 0.1)
				(type default)
			)
			(layer "F.Fab")
		)
		(pad "1" smd circle
			(at -0.40005 0 180)
			(size 0 0)
			(layers "F.Cu" "F.Mask" "F.Paste")
			(net "CLK_100M_GPU_2_R_DP")
		)
		(pad "2" smd circle
			(at 0.40005 0 180)
			(size 0 0)
			(layers "F.Cu" "F.Mask" "F.Paste")
			(net "CLK_100M_GPU_2_DP")
		)
	)
	(footprint ""
		(layer "F.Cu")
		(at 228.410008 -402.994622 90)
		(property "Reference" "PC2223"
			(at 0 0 90)
			(layer "F.SilkS")
			(hide yes)
			(effects
				(font
					(size 1.27 1.27)
				)
			)
		)
		(property "Value" ""
			(at 0 0 90)
			(layer "F.Fab")
			(effects
				(font
					(size 1.27 1.27)
				)
			)
		)
		(duplicate_pad_numbers_are_jumpers no)
		(fp_line
			(start 0.7874 -0.4064)
			(end 0.7874 0.4064)
			(stroke
				(width 0.1524)
				(type default)
			)
			(layer "F.SilkS")
		)
		(fp_line
			(start -0.7874 -0.4064)
			(end 0.7874 -0.4064)
			(stroke
				(width 0.1524)
				(type default)
			)
			(layer "F.SilkS")
		)
		(fp_line
			(start 0.7874 0.4064)
			(end -0.7874 0.4064)
			(stroke
				(width 0.1524)
				(type default)
			)
			(layer "F.SilkS")
		)
		(fp_line
			(start -0.7874 0.4064)
			(end -0.7874 -0.4064)
			(stroke
				(width 0.1524)
				(type default)
			)
			(layer "F.SilkS")
		)
		(fp_line
			(start -0.12065 -0.305054)
			(end -0.12065 -0.2794)
			(stroke
				(width 0.1)
				(type default)
			)
			(layer "F.Fab")
		)
		(fp_line
			(start -0.67945 -0.305054)
			(end -0.12065 -0.305054)
			(stroke
				(width 0.1)
				(type default)
			)
			(layer "F.Fab")
		)
		(fp_line
			(start 0.67945 -0.3048)
			(end 0.67945 0.3048)
			(stroke
				(width 0.1)
				(type default)
			)
			(layer "F.Fab")
		)
		(fp_line
			(start 0.12065 -0.3048)
			(end 0.67945 -0.3048)
			(stroke
				(width 0.1)
				(type default)
			)
			(layer "F.Fab")
		)
		(fp_line
			(start 0.12065 -0.2794)
			(end 0.12065 -0.3048)
			(stroke
				(width 0.1)
				(type default)
			)
			(layer "F.Fab")
		)
		(fp_line
			(start -0.12065 -0.2794)
			(end 0.12065 -0.2794)
			(stroke
				(width 0.1)
				(type default)
			)
			(layer "F.Fab")
		)
		(fp_line
			(start 0.120396 0.2794)
			(end -0.12065 0.2794)
			(stroke
				(width 0.1)
				(type default)
			)
			(layer "F.Fab")
		)
		(fp_line
			(start -0.12065 0.2794)
			(end -0.12065 0.3048)
			(stroke
				(width 0.1)
				(type default)
			)
			(layer "F.Fab")
		)
		(fp_line
			(start 0.67945 0.3048)
			(end 0.120396 0.3048)
			(stroke
				(width 0.1)
				(type default)
			)
			(layer "F.Fab")
		)
		(fp_line
			(start 0.120396 0.3048)
			(end 0.120396 0.2794)
			(stroke
				(width 0.1)
				(type default)
			)
			(layer "F.Fab")
		)
		(fp_line
			(start -0.12065 0.3048)
			(end -0.67945 0.3048)
			(stroke
				(width 0.1)
				(type default)
			)
			(layer "F.Fab")
		)
		(fp_line
			(start -0.67945 0.3048)
			(end -0.67945 -0.305054)
			(stroke
				(width 0.1)
				(type default)
			)
			(layer "F.Fab")
		)
		(pad "1" smd circle
			(at -0.40005 0 90)
			(size 0 0)
			(layers "F.Cu" "F.Mask" "F.Paste")
			(net "HSC_VDD_R_4")
		)
		(pad "2" smd circle
			(at 0.40005 0 90)
			(size 0 0)
			(layers "F.Cu" "F.Mask" "F.Paste")
			(net "AGND_HSC")
		)
	)
	(footprint ""
		(layer "F.Cu")
		(at 236.649768 -352.49993)
		(property "Reference" "H95"
			(at -5.03682 -5.100828 0)
			(unlocked yes)
			(layer "F.SilkS")
			(effects
				(font
					(size 0.7874 0.5842)
					(thickness 0.1524)
				)
				(justify left)
			)
		)
		(property "Value" ""
			(at 0 0 0)
			(layer "F.Fab")
			(effects
				(font
					(size 1.27 1.27)
				)
			)
		)
		(duplicate_pad_numbers_are_jumpers no)
		(pad "1" thru_hole circle
			(at 0 0)
			(size 10.0076 10.0076)
			(drill 5.6134)
			(layers "*.Cu" "*.Mask")
			(remove_unused_layers no)
			(net "GND")
			(clearance -1.9431)
		)
	)
	(footprint ""
		(layer "F.Cu")
		(at 387.62813 -402.371052 -90)
		(property "Reference" "C944"
			(at 0 0 270)
			(layer "F.SilkS")
			(hide yes)
			(effects
				(font
					(size 1.27 1.27)
				)
			)
		)
		(property "Value" ""
			(at 0 0 270)
			(layer "F.Fab")
			(effects
				(font
					(size 1.27 1.27)
				)
			)
		)
		(duplicate_pad_numbers_are_jumpers no)
		(fp_line
			(start -0.299974 0.150114)
			(end -0.299974 -0.150114)
			(stroke
				(width 0.1)
				(type default)
			)
			(layer "F.Fab")
		)
		(fp_line
			(start 0.299974 0.150114)
			(end -0.299974 0.150114)
			(stroke
				(width 0.1)
				(type default)
			)
			(layer "F.Fab")
		)
		(fp_line
			(start -0.299974 -0.150114)
			(end 0.299974 -0.150114)
			(stroke
				(width 0.1)
				(type default)
			)
			(layer "F.Fab")
		)
		(fp_line
			(start 0.299974 -0.150114)
			(end 0.299974 0.150114)
			(stroke
				(width 0.1)
				(type default)
			)
			(layer "F.Fab")
		)
		(pad "1" smd rect
			(at -0.2667 0 270)
			(size 0.3048 0.381)
			(layers "F.Cu" "F.Mask" "F.Paste")
			(net "P5E_CPU0_PE2_TX_C_DN<10>")
		)
		(pad "2" smd rect
			(at 0.2667 0 270)
			(size 0.3048 0.381)
			(layers "F.Cu" "F.Mask" "F.Paste")
			(net "P5E_CPU0_PE2_TX_DN<10>")
		)
	)
)
